# SCM (Grand Teton) — schematic netlist excerpt (pin names and nets, part order shuffled) for the footprints in the layout excerpt that follows; sources: Cadence DE-HDL packaged netlist, KiCad conversion of 12092022_DA0F0TMDCD0_F0T_Management_Board_D_brd_V3_OCP.brd

R168  Q_RES  33.2 1% CHIP  pkg 0402LF  page 12 : A = RST_PLTRST_N ; B = RST_PLTRST_R_N
C277  Q_CAP  1UF 25V 10% X6S  pkg C0402  page 17 : A = ADCVREFEXT1 ; B = GND

(kicad_pcb
	(version 20260206)
	(generator "pcbnew")
	(generator_version "10.0")
	(general
		(thickness 1.6)
		(legacy_teardrops no)
	)
	(paper "A4")
	(title_block
		(title "12092022_DA0F0TMDCD0_F0T_Management_Board_D_brd_V3_OCP.brd")
		(comment 1 "Grand Teton / footprints 862-863 of 1440")
	)
	(layers
		(0 "F.Cu" signal "TOP")
		(4 "In1.Cu" signal "GND")
		(6 "In2.Cu" signal "IN1")
		(8 "In3.Cu" signal "GND1")
		(10 "In4.Cu" signal "IN2")
		(12 "In5.Cu" signal "VCC")
		(14 "In6.Cu" signal "VCC1")
		(16 "In7.Cu" signal "IN3")
		(18 "In8.Cu" signal "GND2")
		(20 "In9.Cu" signal "IN4")
		(22 "In10.Cu" signal "GND3")
		(2 "B.Cu" signal "BOTTOM")
		(9 "F.Adhes" user "F.Adhesive")
		(11 "B.Adhes" user "B.Adhesive")
		(13 "F.Paste" user "Package Geometry/Pastemask Top")
		(15 "B.Paste" user "Package Geometry/Pastemask Bottom")
		(5 "F.SilkS" user "Ref Des/Silkscreen Top")
		(7 "B.SilkS" user "Ref Des/Silkscreen Bottom")
		(1 "F.Mask" user "Board Geometry/Soldermask Top")
		(3 "B.Mask" user "Board Geometry/Soldermask Bottom")
		(17 "Dwgs.User" user "User.Drawings")
		(19 "Cmts.User" user "User.Comments")
		(21 "Eco1.User" user "User.Eco1")
		(23 "Eco2.User" user "User.Eco2")
		(25 "Edge.Cuts" user "Board Geometry/Outline")
		(27 "Margin" user)
		(31 "F.CrtYd" user "Package Geometry/Place Bound Top")
		(29 "B.CrtYd" user "Package Geometry/Place Bound Bottom")
		(35 "F.Fab" user "Ref Des/Assembly Top")
		(33 "B.Fab" user "Ref Des/Assembly Bottom")
	)
	(footprint ""
		(layer "B.Cu")
		(at 41.91 -43.053 180)
		(property "Reference" "R168"
			(at 0 0 0)
			(layer "B.SilkS")
			(hide yes)
			(effects
				(font
					(size 1.27 1.27)
				)
				(justify mirror)
			)
		)
		(property "Value" ""
			(at 0 0 0)
			(layer "B.Fab")
			(effects
				(font
					(size 1.27 1.27)
				)
				(justify mirror)
			)
		)
		(duplicate_pad_numbers_are_jumpers no)
		(fp_line
			(start 0.7874 0.4064)
			(end 0.7874 -0.4064)
			(stroke
				(width 0.1524)
				(type default)
			)
			(layer "B.SilkS")
		)
		(fp_line
			(start 0.7874 -0.4064)
			(end -0.7874 -0.4064)
			(stroke
				(width 0.1524)
				(type default)
			)
			(layer "B.SilkS")
		)
		(fp_line
			(start -0.7874 0.4064)
			(end 0.7874 0.4064)
			(stroke
				(width 0.1524)
				(type default)
			)
			(layer "B.SilkS")
		)
		(fp_line
			(start -0.7874 -0.4064)
			(end -0.7874 0.4064)
			(stroke
				(width 0.1524)
				(type default)
			)
			(layer "B.SilkS")
		)
		(fp_line
			(start 0.67945 0.3048)
			(end 0.67945 -0.305054)
			(stroke
				(width 0.1)
				(type default)
			)
			(layer "B.Fab")
		)
		(fp_line
			(start 0.67945 -0.305054)
			(end 0.12065 -0.305054)
			(stroke
				(width 0.1)
				(type default)
			)
			(layer "B.Fab")
		)
		(fp_line
			(start 0.12065 0.3048)
			(end 0.67945 0.3048)
			(stroke
				(width 0.1)
				(type default)
			)
			(layer "B.Fab")
		)
		(fp_line
			(start 0.12065 0.2794)
			(end 0.12065 0.3048)
			(stroke
				(width 0.1)
				(type default)
			)
			(layer "B.Fab")
		)
		(fp_line
			(start 0.12065 -0.2794)
			(end -0.12065 -0.2794)
			(stroke
				(width 0.1)
				(type default)
			)
			(layer "B.Fab")
		)
		(fp_line
			(start 0.12065 -0.305054)
			(end 0.12065 -0.2794)
			(stroke
				(width 0.1)
				(type default)
			)
			(layer "B.Fab")
		)
		(fp_line
			(start -0.120396 0.3048)
			(end -0.120396 0.2794)
			(stroke
				(width 0.1)
				(type default)
			)
			(layer "B.Fab")
		)
		(fp_line
			(start -0.120396 0.2794)
			(end 0.12065 0.2794)
			(stroke
				(width 0.1)
				(type default)
			)
			(layer "B.Fab")
		)
		(fp_line
			(start -0.12065 -0.2794)
			(end -0.12065 -0.3048)
			(stroke
				(width 0.1)
				(type default)
			)
			(layer "B.Fab")
		)
		(fp_line
			(start -0.12065 -0.3048)
			(end -0.67945 -0.3048)
			(stroke
				(width 0.1)
				(type default)
			)
			(layer "B.Fab")
		)
		(fp_line
			(start -0.67945 0.3048)
			(end -0.120396 0.3048)
			(stroke
				(width 0.1)
				(type default)
			)
			(layer "B.Fab")
		)
		(fp_line
			(start -0.67945 -0.3048)
			(end -0.67945 0.3048)
			(stroke
				(width 0.1)
				(type default)
			)
			(layer "B.Fab")
		)
		(pad "1" smd circle
			(at 0.40005 0)
			(size 0 0)
			(layers "B.Cu" "B.Mask" "B.Paste")
			(net "RST_PLTRST_N")
		)
		(pad "2" smd circle
			(at -0.40005 0)
			(size 0 0)
			(layers "B.Cu" "B.Mask" "B.Paste")
			(net "RST_PLTRST_R_N")
		)
	)
	(footprint ""
		(layer "B.Cu")
		(at 52.891182 -70.799706)
		(property "Reference" "C277"
			(at 0 0 0)
			(layer "B.SilkS")
			(hide yes)
			(effects
				(font
					(size 1.27 1.27)
				)
				(justify mirror)
			)
		)
		(property "Value" ""
			(at 0 0 0)
			(layer "B.Fab")
			(effects
				(font
					(size 1.27 1.27)
				)
				(justify mirror)
			)
		)
		(duplicate_pad_numbers_are_jumpers no)
		(fp_line
			(start -0.7874 -0.4064)
			(end -0.7874 0.4064)
			(stroke
				(width 0.1524)
				(type default)
			)
			(layer "B.SilkS")
		)
		(fp_line
			(start -0.7874 0.4064)
			(end 0.7874 0.4064)
			(stroke
				(width 0.1524)
				(type default)
			)
			(layer "B.SilkS")
		)
		(fp_line
			(start 0.7874 -0.4064)
			(end -0.7874 -0.4064)
			(stroke
				(width 0.1524)
				(type default)
			)
			(layer "B.SilkS")
		)
		(fp_line
			(start 0.7874 0.4064)
			(end 0.7874 -0.4064)
			(stroke
				(width 0.1524)
				(type default)
			)
			(layer "B.SilkS")
		)
		(fp_line
			(start -0.67945 -0.3048)
			(end -0.67945 0.3048)
			(stroke
				(width 0.1)
				(type default)
			)
			(layer "B.Fab")
		)
		(fp_line
			(start -0.67945 0.3048)
			(end -0.120396 0.3048)
			(stroke
				(width 0.1)
				(type default)
			)
			(layer "B.Fab")
		)
		(fp_line
			(start -0.12065 -0.3048)
			(end -0.67945 -0.3048)
			(stroke
				(width 0.1)
				(type default)
			)
			(layer "B.Fab")
		)
		(fp_line
			(start -0.12065 -0.2794)
			(end -0.12065 -0.3048)
			(stroke
				(width 0.1)
				(type default)
			)
			(layer "B.Fab")
		)
		(fp_line
			(start -0.120396 0.2794)
			(end 0.12065 0.2794)
			(stroke
				(width 0.1)
				(type default)
			)
			(layer "B.Fab")
		)
		(fp_line
			(start -0.120396 0.3048)
			(end -0.120396 0.2794)
			(stroke
				(width 0.1)
				(type default)
			)
			(layer "B.Fab")
		)
		(fp_line
			(start 0.12065 -0.305054)
			(end 0.12065 -0.2794)
			(stroke
				(width 0.1)
				(type default)
			)
			(layer "B.Fab")
		)
		(fp_line
			(start 0.12065 -0.2794)
			(end -0.12065 -0.2794)
			(stroke
				(width 0.1)
				(type default)
			)
			(layer "B.Fab")
		)
		(fp_line
			(start 0.12065 0.2794)
			(end 0.12065 0.3048)
			(stroke
				(width 0.1)
				(type default)
			)
			(layer "B.Fab")
		)
		(fp_line
			(start 0.12065 0.3048)
			(end 0.67945 0.3048)
			(stroke
				(width 0.1)
				(type default)
			)
			(layer "B.Fab")
		)
		(fp_line
			(start 0.67945 -0.305054)
			(end 0.12065 -0.305054)
			(stroke
				(width 0.1)
				(type default)
			)
			(layer "B.Fab")
		)
		(fp_line
			(start 0.67945 0.3048)
			(end 0.67945 -0.305054)
			(stroke
				(width 0.1)
				(type default)
			)
			(layer "B.Fab")
		)
		(pad "1" smd circle
			(at 0.40005 0 180)
			(size 0 0)
			(layers "B.Cu" "B.Mask" "B.Paste")
			(net "ADCVREFEXT1")
		)
		(pad "2" smd circle
			(at -0.40005 0 180)
			(size 0 0)
			(layers "B.Cu" "B.Mask" "B.Paste")
			(net "GND")
		)
	)
)
